# S9S_MB_2U (Grand Teton) — schematic netlist excerpt (pin names and nets, part order shuffled) for the footprints in the layout excerpt that follows; sources: Cadence DE-HDL packaged netlist, KiCad conversion of 03242023_DA0F0TMBIJ0_F0T_Motherboard_J_brd_V01_OCP.brd

R47  Q_RES  84.5K 1% CHIP  pkg 0402LF  page 103 : A = PD_CHC_CPU1_DIMM2_SAA ; B = GND
R671  Q_RES  33.2 1% CHIP  pkg 0402LF  page 230 : A = I3C_SPD_DDRABCD_CPU1_SDA ; B = I3C_SPD_DDRABCD_CPU1_R_SDA

(kicad_pcb
	(version 20260206)
	(generator "pcbnew")
	(generator_version "10.0")
	(general
		(thickness 1.6)
		(legacy_teardrops no)
	)
	(paper "A4")
	(title_block
		(title "03242023_DA0F0TMBIJ0_F0T_Motherboard_J_brd_V01_OCP.brd")
		(comment 1 "Grand Teton / footprints 4876-4877 of 6105")
	)
	(layers
		(0 "F.Cu" signal "TOP")
		(4 "In1.Cu" signal "GND")
		(6 "In2.Cu" signal "IN1")
		(8 "In3.Cu" signal "GND1")
		(10 "In4.Cu" signal "IN2")
		(12 "In5.Cu" signal "GND2")
		(14 "In6.Cu" signal "IN3")
		(16 "In7.Cu" signal "GND3")
		(18 "In8.Cu" signal "VCC")
		(20 "In9.Cu" signal "VCC1")
		(22 "In10.Cu" signal "GND4")
		(24 "In11.Cu" signal "IN4")
		(26 "In12.Cu" signal "GND5")
		(28 "In13.Cu" signal "IN5")
		(30 "In14.Cu" signal "GND6")
		(32 "In15.Cu" signal "IN6")
		(34 "In16.Cu" signal "GND7")
		(2 "B.Cu" signal "BOTTOM")
		(9 "F.Adhes" user "F.Adhesive")
		(11 "B.Adhes" user "B.Adhesive")
		(13 "F.Paste" user "Package Geometry/Pastemask Top")
		(15 "B.Paste" user "Package Geometry/Pastemask Bottom")
		(5 "F.SilkS" user "Ref Des/Silkscreen Top")
		(7 "B.SilkS" user "Ref Des/Silkscreen Bottom")
		(1 "F.Mask" user "Board Geometry/Soldermask Top")
		(3 "B.Mask" user "Board Geometry/Soldermask Bottom")
		(17 "Dwgs.User" user "User.Drawings")
		(19 "Cmts.User" user "User.Comments")
		(21 "Eco1.User" user "User.Eco1")
		(23 "Eco2.User" user "User.Eco2")
		(25 "Edge.Cuts" user "Board Geometry/Outline")
		(27 "Margin" user)
		(31 "F.CrtYd" user "Package Geometry/Place Bound Top")
		(29 "B.CrtYd" user "Package Geometry/Place Bound Bottom")
		(35 "F.Fab" user "Ref Des/Assembly Top")
		(33 "B.Fab" user "Ref Des/Assembly Bottom")
	)
	(footprint ""
		(layer "B.Cu")
		(at 95.225108 -190.705232 90)
		(property "Reference" "R671"
			(at 0 0 90)
			(layer "B.SilkS")
			(hide yes)
			(effects
				(font
					(size 1.27 1.27)
				)
				(justify mirror)
			)
		)
		(property "Value" ""
			(at 0 0 90)
			(layer "B.Fab")
			(effects
				(font
					(size 1.27 1.27)
				)
				(justify mirror)
			)
		)
		(duplicate_pad_numbers_are_jumpers no)
		(fp_line
			(start 0.7874 -0.4064)
			(end -0.7874 -0.4064)
			(stroke
				(width 0.1524)
				(type default)
			)
			(layer "B.SilkS")
		)
		(fp_line
			(start -0.7874 -0.4064)
			(end -0.7874 0.4064)
			(stroke
				(width 0.1524)
				(type default)
			)
			(layer "B.SilkS")
		)
		(fp_line
			(start 0.7874 0.4064)
			(end 0.7874 -0.4064)
			(stroke
				(width 0.1524)
				(type default)
			)
			(layer "B.SilkS")
		)
		(fp_line
			(start -0.7874 0.4064)
			(end 0.7874 0.4064)
			(stroke
				(width 0.1524)
				(type default)
			)
			(layer "B.SilkS")
		)
		(fp_line
			(start 0.67945 -0.305054)
			(end 0.12065 -0.305054)
			(stroke
				(width 0.1)
				(type default)
			)
			(layer "B.Fab")
		)
		(fp_line
			(start 0.12065 -0.305054)
			(end 0.12065 -0.2794)
			(stroke
				(width 0.1)
				(type default)
			)
			(layer "B.Fab")
		)
		(fp_line
			(start -0.12065 -0.3048)
			(end -0.67945 -0.3048)
			(stroke
				(width 0.1)
				(type default)
			)
			(layer "B.Fab")
		)
		(fp_line
			(start -0.67945 -0.3048)
			(end -0.67945 0.3048)
			(stroke
				(width 0.1)
				(type default)
			)
			(layer "B.Fab")
		)
		(fp_line
			(start 0.12065 -0.2794)
			(end -0.12065 -0.2794)
			(stroke
				(width 0.1)
				(type default)
			)
			(layer "B.Fab")
		)
		(fp_line
			(start -0.12065 -0.2794)
			(end -0.12065 -0.3048)
			(stroke
				(width 0.1)
				(type default)
			)
			(layer "B.Fab")
		)
		(fp_line
			(start 0.12065 0.2794)
			(end 0.12065 0.3048)
			(stroke
				(width 0.1)
				(type default)
			)
			(layer "B.Fab")
		)
		(fp_line
			(start -0.120396 0.2794)
			(end 0.12065 0.2794)
			(stroke
				(width 0.1)
				(type default)
			)
			(layer "B.Fab")
		)
		(fp_line
			(start 0.67945 0.3048)
			(end 0.67945 -0.305054)
			(stroke
				(width 0.1)
				(type default)
			)
			(layer "B.Fab")
		)
		(fp_line
			(start 0.12065 0.3048)
			(end 0.67945 0.3048)
			(stroke
				(width 0.1)
				(type default)
			)
			(layer "B.Fab")
		)
		(fp_line
			(start -0.120396 0.3048)
			(end -0.120396 0.2794)
			(stroke
				(width 0.1)
				(type default)
			)
			(layer "B.Fab")
		)
		(fp_line
			(start -0.67945 0.3048)
			(end -0.120396 0.3048)
			(stroke
				(width 0.1)
				(type default)
			)
			(layer "B.Fab")
		)
		(pad "1" smd circle
			(at 0.40005 0 270)
			(size 0 0)
			(layers "B.Cu" "B.Mask" "B.Paste")
			(net "I3C_SPD_DDRABCD_CPU1_SDA")
		)
		(pad "2" smd circle
			(at -0.40005 0 270)
			(size 0 0)
			(layers "B.Cu" "B.Mask" "B.Paste")
			(net "I3C_SPD_DDRABCD_CPU1_R_SDA")
		)
	)
	(footprint ""
		(layer "B.Cu")
		(at 32.557212 -318.650112)
		(property "Reference" "R47"
			(at 0 0 0)
			(layer "B.SilkS")
			(hide yes)
			(effects
				(font
					(size 1.27 1.27)
				)
				(justify mirror)
			)
		)
		(property "Value" ""
			(at 0 0 0)
			(layer "B.Fab")
			(effects
				(font
					(size 1.27 1.27)
				)
				(justify mirror)
			)
		)
		(duplicate_pad_numbers_are_jumpers no)
		(fp_line
			(start -0.7874 -0.4064)
			(end -0.7874 0.4064)
			(stroke
				(width 0.1524)
				(type default)
			)
			(layer "B.SilkS")
		)
		(fp_line
			(start -0.7874 0.4064)
			(end 0.7874 0.4064)
			(stroke
				(width 0.1524)
				(type default)
			)
			(layer "B.SilkS")
		)
		(fp_line
			(start 0.7874 -0.4064)
			(end -0.7874 -0.4064)
			(stroke
				(width 0.1524)
				(type default)
			)
			(layer "B.SilkS")
		)
		(fp_line
			(start 0.7874 0.4064)
			(end 0.7874 -0.4064)
			(stroke
				(width 0.1524)
				(type default)
			)
			(layer "B.SilkS")
		)
		(fp_line
			(start -0.67945 -0.3048)
			(end -0.67945 0.3048)
			(stroke
				(width 0.1)
				(type default)
			)
			(layer "B.Fab")
		)
		(fp_line
			(start -0.67945 0.3048)
			(end -0.120396 0.3048)
			(stroke
				(width 0.1)
				(type default)
			)
			(layer "B.Fab")
		)
		(fp_line
			(start -0.12065 -0.3048)
			(end -0.67945 -0.3048)
			(stroke
				(width 0.1)
				(type default)
			)
			(layer "B.Fab")
		)
		(fp_line
			(start -0.12065 -0.2794)
			(end -0.12065 -0.3048)
			(stroke
				(width 0.1)
				(type default)
			)
			(layer "B.Fab")
		)
		(fp_line
			(start -0.120396 0.2794)
			(end 0.12065 0.2794)
			(stroke
				(width 0.1)
				(type default)
			)
			(layer "B.Fab")
		)
		(fp_line
			(start -0.120396 0.3048)
			(end -0.120396 0.2794)
			(stroke
				(width 0.1)
				(type default)
			)
			(layer "B.Fab")
		)
		(fp_line
			(start 0.12065 -0.305054)
			(end 0.12065 -0.2794)
			(stroke
				(width 0.1)
				(type default)
			)
			(layer "B.Fab")
		)
		(fp_line
			(start 0.12065 -0.2794)
			(end -0.12065 -0.2794)
			(stroke
				(width 0.1)
				(type default)
			)
			(layer "B.Fab")
		)
		(fp_line
			(start 0.12065 0.2794)
			(end 0.12065 0.3048)
			(stroke
				(width 0.1)
				(type default)
			)
			(layer "B.Fab")
		)
		(fp_line
			(start 0.12065 0.3048)
			(end 0.67945 0.3048)
			(stroke
				(width 0.1)
				(type default)
			)
			(layer "B.Fab")
		)
		(fp_line
			(start 0.67945 -0.305054)
			(end 0.12065 -0.305054)
			(stroke
				(width 0.1)
				(type default)
			)
			(layer "B.Fab")
		)
		(fp_line
			(start 0.67945 0.3048)
			(end 0.67945 -0.305054)
			(stroke
				(width 0.1)
				(type default)
			)
			(layer "B.Fab")
		)
		(pad "1" smd circle
			(at 0.40005 0 180)
			(size 0 0)
			(layers "B.Cu" "B.Mask" "B.Paste")
			(net "PD_CHC_CPU1_DIMM2_SAA")
		)
		(pad "2" smd circle
			(at -0.40005 0 180)
			(size 0 0)
			(layers "B.Cu" "B.Mask" "B.Paste")
			(net "GND")
		)
	)
)
